(kicad_pcb
	(version 20260206)
	(generator "pcbnew")
	(generator_version "10.0")
	(general
		(thickness 1.6)
		(legacy_teardrops no)
	)
	(paper "A4")
	(title_block
		(title "03242023_DA0F0TMBIJ0_F0T_Motherboard_J_brd_V01_OCP.brd")
		(comment 1 "Grand Teton / footprints 5229-5233 of 6105")
	)
	(layers
		(0 "F.Cu" signal "TOP")
		(4 "In1.Cu" signal "GND")
		(6 "In2.Cu" signal "IN1")
		(8 "In3.Cu" signal "GND1")
		(10 "In4.Cu" signal "IN2")
		(12 "In5.Cu" signal "GND2")
		(14 "In6.Cu" signal "IN3")
		(16 "In7.Cu" signal "GND3")
		(18 "In8.Cu" signal "VCC")
		(20 "In9.Cu" signal "VCC1")
		(22 "In10.Cu" signal "GND4")
		(24 "In11.Cu" signal "IN4")
		(26 "In12.Cu" signal "GND5")
		(28 "In13.Cu" signal "IN5")
		(30 "In14.Cu" signal "GND6")
		(32 "In15.Cu" signal "IN6")
		(34 "In16.Cu" signal "GND7")
		(2 "B.Cu" signal "BOTTOM")
		(9 "F.Adhes" user "F.Adhesive")
		(11 "B.Adhes" user "B.Adhesive")
		(13 "F.Paste" user "Package Geometry/Pastemask Top")
		(15 "B.Paste" user "Package Geometry/Pastemask Bottom")
		(5 "F.SilkS" user "Ref Des/Silkscreen Top")
		(7 "B.SilkS" user "Ref Des/Silkscreen Bottom")
		(1 "F.Mask" user "Board Geometry/Soldermask Top")
		(3 "B.Mask" user "Board Geometry/Soldermask Bottom")
		(17 "Dwgs.User" user "User.Drawings")
		(19 "Cmts.User" user "User.Comments")
		(21 "Eco1.User" user "User.Eco1")
		(23 "Eco2.User" user "User.Eco2")
		(25 "Edge.Cuts" user "Board Geometry/Outline")
		(27 "Margin" user)
		(31 "F.CrtYd" user "Package Geometry/Place Bound Top")
		(29 "B.CrtYd" user "Package Geometry/Place Bound Bottom")
		(35 "F.Fab" user "Ref Des/Assembly Top")
		(33 "B.Fab" user "Ref Des/Assembly Bottom")
	)
	(footprint ""
		(layer "B.Cu")
		(at 287.448498 -403.031452 90)
		(property "Reference" "PR2519"
			(at 0 0 90)
			(layer "B.SilkS")
			(hide yes)
			(effects
				(font
					(size 1.27 1.27)
				)
				(justify mirror)
			)
		)
		(property "Value" ""
			(at 0 0 90)
			(layer "B.Fab")
			(effects
				(font
					(size 1.27 1.27)
				)
				(justify mirror)
			)
		)
		(duplicate_pad_numbers_are_jumpers no)
		(fp_line
			(start 0.7874 -0.4064)
			(end -0.7874 -0.4064)
			(stroke
				(width 0.1524)
				(type default)
			)
			(layer "B.SilkS")
		)
		(fp_line
			(start -0.7874 -0.4064)
			(end -0.7874 0.4064)
			(stroke
				(width 0.1524)
				(type default)
			)
			(layer "B.SilkS")
		)
		(fp_line
			(start 0.7874 0.4064)
			(end 0.7874 -0.4064)
			(stroke
				(width 0.1524)
				(type default)
			)
			(layer "B.SilkS")
		)
		(fp_line
			(start -0.7874 0.4064)
			(end 0.7874 0.4064)
			(stroke
				(width 0.1524)
				(type default)
			)
			(layer "B.SilkS")
		)
		(fp_line
			(start 0.67945 -0.305054)
			(end 0.12065 -0.305054)
			(stroke
				(width 0.1)
				(type default)
			)
			(layer "B.Fab")
		)
		(fp_line
			(start 0.12065 -0.305054)
			(end 0.12065 -0.2794)
			(stroke
				(width 0.1)
				(type default)
			)
			(layer "B.Fab")
		)
		(fp_line
			(start -0.12065 -0.3048)
			(end -0.67945 -0.3048)
			(stroke
				(width 0.1)
				(type default)
			)
			(layer "B.Fab")
		)
		(fp_line
			(start -0.67945 -0.3048)
			(end -0.67945 0.3048)
			(stroke
				(width 0.1)
				(type default)
			)
			(layer "B.Fab")
		)
		(fp_line
			(start 0.12065 -0.2794)
			(end -0.12065 -0.2794)
			(stroke
				(width 0.1)
				(type default)
			)
			(layer "B.Fab")
		)
		(fp_line
			(start -0.12065 -0.2794)
			(end -0.12065 -0.3048)
			(stroke
				(width 0.1)
				(type default)
			)
			(layer "B.Fab")
		)
		(fp_line
			(start 0.12065 0.2794)
			(end 0.12065 0.3048)
			(stroke
				(width 0.1)
				(type default)
			)
			(layer "B.Fab")
		)
		(fp_line
			(start -0.120396 0.2794)
			(end 0.12065 0.2794)
			(stroke
				(width 0.1)
				(type default)
			)
			(layer "B.Fab")
		)
		(fp_line
			(start 0.67945 0.3048)
			(end 0.67945 -0.305054)
			(stroke
				(width 0.1)
				(type default)
			)
			(layer "B.Fab")
		)
		(fp_line
			(start 0.12065 0.3048)
			(end 0.67945 0.3048)
			(stroke
				(width 0.1)
				(type default)
			)
			(layer "B.Fab")
		)
		(fp_line
			(start -0.120396 0.3048)
			(end -0.120396 0.2794)
			(stroke
				(width 0.1)
				(type default)
			)
			(layer "B.Fab")
		)
		(fp_line
			(start -0.67945 0.3048)
			(end -0.120396 0.3048)
			(stroke
				(width 0.1)
				(type default)
			)
			(layer "B.Fab")
		)
		(pad "1" smd circle
			(at 0.40005 0 270)
			(size 0 0)
			(layers "B.Cu" "B.Mask" "B.Paste")
			(net "P12V_HSC_ADC_N")
		)
		(pad "2" smd circle
			(at -0.40005 0 270)
			(size 0 0)
			(layers "B.Cu" "B.Mask" "B.Paste")
			(net "P12V_HSC_SENSE1_N")
		)
	)
	(footprint ""
		(layer "B.Cu")
		(at 75.745594 -45.536866 90)
		(property "Reference" "C2020"
			(at 0 0 90)
			(layer "B.SilkS")
			(hide yes)
			(effects
				(font
					(size 1.27 1.27)
				)
				(justify mirror)
			)
		)
		(property "Value" ""
			(at 0 0 90)
			(layer "B.Fab")
			(effects
				(font
					(size 1.27 1.27)
				)
				(justify mirror)
			)
		)
		(duplicate_pad_numbers_are_jumpers no)
		(fp_line
			(start 0.7874 -0.4064)
			(end -0.7874 -0.4064)
			(stroke
				(width 0.1524)
				(type default)
			)
			(layer "B.SilkS")
		)
		(fp_line
			(start -0.7874 -0.4064)
			(end -0.7874 0.4064)
			(stroke
				(width 0.1524)
				(type default)
			)
			(layer "B.SilkS")
		)
		(fp_line
			(start 0.7874 0.4064)
			(end 0.7874 -0.4064)
			(stroke
				(width 0.1524)
				(type default)
			)
			(layer "B.SilkS")
		)
		(fp_line
			(start -0.7874 0.4064)
			(end 0.7874 0.4064)
			(stroke
				(width 0.1524)
				(type default)
			)
			(layer "B.SilkS")
		)
		(fp_line
			(start 0.67945 -0.305054)
			(end 0.12065 -0.305054)
			(stroke
				(width 0.1)
				(type default)
			)
			(layer "B.Fab")
		)
		(fp_line
			(start 0.12065 -0.305054)
			(end 0.12065 -0.2794)
			(stroke
				(width 0.1)
				(type default)
			)
			(layer "B.Fab")
		)
		(fp_line
			(start -0.12065 -0.3048)
			(end -0.67945 -0.3048)
			(stroke
				(width 0.1)
				(type default)
			)
			(layer "B.Fab")
		)
		(fp_line
			(start -0.67945 -0.3048)
			(end -0.67945 0.3048)
			(stroke
				(width 0.1)
				(type default)
			)
			(layer "B.Fab")
		)
		(fp_line
			(start 0.12065 -0.2794)
			(end -0.12065 -0.2794)
			(stroke
				(width 0.1)
				(type default)
			)
			(layer "B.Fab")
		)
		(fp_line
			(start -0.12065 -0.2794)
			(end -0.12065 -0.3048)
			(stroke
				(width 0.1)
				(type default)
			)
			(layer "B.Fab")
		)
		(fp_line
			(start 0.12065 0.2794)
			(end 0.12065 0.3048)
			(stroke
				(width 0.1)
				(type default)
			)
			(layer "B.Fab")
		)
		(fp_line
			(start -0.120396 0.2794)
			(end 0.12065 0.2794)
			(stroke
				(width 0.1)
				(type default)
			)
			(layer "B.Fab")
		)
		(fp_line
			(start 0.67945 0.3048)
			(end 0.67945 -0.305054)
			(stroke
				(width 0.1)
				(type default)
			)
			(layer "B.Fab")
		)
		(fp_line
			(start 0.12065 0.3048)
			(end 0.67945 0.3048)
			(stroke
				(width 0.1)
				(type default)
			)
			(layer "B.Fab")
		)
		(fp_line
			(start -0.120396 0.3048)
			(end -0.120396 0.2794)
			(stroke
				(width 0.1)
				(type default)
			)
			(layer "B.Fab")
		)
		(fp_line
			(start -0.67945 0.3048)
			(end -0.120396 0.3048)
			(stroke
				(width 0.1)
				(type default)
			)
			(layer "B.Fab")
		)
		(pad "1" smd circle
			(at 0.40005 0 270)
			(size 0 0)
			(layers "B.Cu" "B.Mask" "B.Paste")
			(net "VSENSE_P12V_INA230_3_INP")
		)
		(pad "2" smd circle
			(at -0.40005 0 270)
			(size 0 0)
			(layers "B.Cu" "B.Mask" "B.Paste")
			(net "VSENSE_P12V_INA230_3_INN")
		)
	)
	(footprint ""
		(layer "B.Cu")
		(at 378.099574 2.923794)
		(property "Reference" "J117"
			(at 4.651756 1.394206 270)
			(unlocked yes)
			(layer "B.SilkS")
			(effects
				(font
					(size 0.7874 0.5842)
					(thickness 0.1524)
				)
				(justify left mirror)
			)
		)
		(property "Value" ""
			(at 0 0 0)
			(layer "B.Fab")
			(effects
				(font
					(size 1.27 1.27)
				)
				(justify mirror)
			)
		)
		(duplicate_pad_numbers_are_jumpers no)
		(fp_line
			(start -1.2192 -2.1082)
			(end -1.2192 2.1082)
			(stroke
				(width 0.1524)
				(type default)
			)
			(layer "B.SilkS")
		)
		(fp_line
			(start -1.2192 2.1082)
			(end 1.2192 2.1082)
			(stroke
				(width 0.1524)
				(type default)
			)
			(layer "B.SilkS")
		)
		(fp_line
			(start 1.2192 -2.1082)
			(end -1.2192 -2.1082)
			(stroke
				(width 0.1524)
				(type default)
			)
			(layer "B.SilkS")
		)
		(fp_line
			(start 1.2192 2.1082)
			(end 1.2192 -2.1082)
			(stroke
				(width 0.1524)
				(type default)
			)
			(layer "B.SilkS")
		)
		(pad "" np_thru_hole circle
			(at -3.4671 -1.27 270)
			(size 1.0414 1.0414)
			(drill 1.0414)
			(layers "*.Cu" "*.Mask")
			(clearance 0.381)
			(thermal_gap 0.381)
		)
		(pad "" np_thru_hole circle
			(at -3.4671 1.27 270)
			(size 1.0414 1.0414)
			(drill 1.0414)
			(layers "*.Cu" "*.Mask")
			(clearance 0.381)
			(thermal_gap 0.381)
		)
		(pad "" np_thru_hole circle
			(at 2.8829 -1.27 270)
			(size 1.0414 1.0414)
			(drill 1.0414)
			(layers "*.Cu" "*.Mask")
			(clearance 0.381)
			(thermal_gap 0.381)
		)
		(pad "" np_thru_hole circle
			(at 2.8829 1.27 270)
			(size 1.0414 1.0414)
			(drill 1.0414)
			(layers "*.Cu" "*.Mask")
			(clearance 0.381)
			(thermal_gap 0.381)
		)
		(pad "1" smd rect
			(at -0.8255 -0.249936 270)
			(size 0.3048 0.508)
			(layers "B.Cu" "B.Mask" "B.Paste")
			(net "DELTA_L_85_5INCH_IN6_DN")
		)
		(pad "2" smd rect
			(at -0.8255 0.249936 270)
			(size 0.3048 0.508)
			(layers "B.Cu" "B.Mask" "B.Paste")
			(net "DELTA_L_85_5INCH_IN6_DP")
		)
		(pad "3" smd circle
			(at 0 0 180)
			(size 0 0)
			(layers "B.Cu" "B.Mask" "B.Paste")
			(net "DELTA_L_GND_1")
		)
		(zone
			(layers "F.Cu" "B.Cu" "In1.Cu" "In2.Cu" "In3.Cu" "In4.Cu" "In5.Cu" "In6.Cu"
				"In7.Cu" "In8.Cu" "In9.Cu" "In10.Cu" "In11.Cu" "In12.Cu" "In13.Cu" "In14.Cu"
				"In15.Cu" "In16.Cu"
			)
			(hatch none 0.5)
			(connect_pads
				(clearance 0)
			)
			(min_thickness 0.25)
			(keepout
				(tracks not_allowed)
				(vias allowed)
				(pads allowed)
				(copperpour not_allowed)
				(footprints allowed)
			)
			(placement
				(enabled no)
				(sheetname "")
			)
			(fill
				(thermal_gap 0.5)
				(thermal_bridge_width 0.5)
				(island_removal_mode 0)
			)
			(polygon
				(pts
					(arc
						(start 375.559574 1.653794)
						(mid 373.705374 1.653794)
						(end 375.559574 1.653794)
					)
				)
			)
		)
		(zone
			(layers "F.Cu" "B.Cu" "In1.Cu" "In2.Cu" "In3.Cu" "In4.Cu" "In5.Cu" "In6.Cu"
				"In7.Cu" "In8.Cu" "In9.Cu" "In10.Cu" "In11.Cu" "In12.Cu" "In13.Cu" "In14.Cu"
				"In15.Cu" "In16.Cu"
			)
			(hatch none 0.5)
			(connect_pads
				(clearance 0)
			)
			(min_thickness 0.25)
			(keepout
				(tracks not_allowed)
				(vias allowed)
				(pads allowed)
				(copperpour not_allowed)
				(footprints allowed)
			)
			(placement
				(enabled no)
				(sheetname "")
			)
			(fill
				(thermal_gap 0.5)
				(thermal_bridge_width 0.5)
				(island_removal_mode 0)
			)
			(polygon
				(pts
					(arc
						(start 375.559574 4.193794)
						(mid 373.705374 4.193794)
						(end 375.559574 4.193794)
					)
				)
			)
		)
		(zone
			(layers "F.Cu" "B.Cu" "In1.Cu" "In2.Cu" "In3.Cu" "In4.Cu" "In5.Cu" "In6.Cu"
				"In7.Cu" "In8.Cu" "In9.Cu" "In10.Cu" "In11.Cu" "In12.Cu" "In13.Cu" "In14.Cu"
				"In15.Cu" "In16.Cu"
			)
			(hatch none 0.5)
			(connect_pads
				(clearance 0)
			)
			(min_thickness 0.25)
			(keepout
				(tracks not_allowed)
				(vias allowed)
				(pads allowed)
				(copperpour not_allowed)
				(footprints allowed)
			)
			(placement
				(enabled no)
				(sheetname "")
			)
			(fill
				(thermal_gap 0.5)
				(thermal_bridge_width 0.5)
				(island_removal_mode 0)
			)
			(polygon
				(pts
					(arc
						(start 381.909574 1.653794)
						(mid 380.055374 1.653794)
						(end 381.909574 1.653794)
					)
				)
			)
		)
		(zone
			(layers "F.Cu" "B.Cu" "In1.Cu" "In2.Cu" "In3.Cu" "In4.Cu" "In5.Cu" "In6.Cu"
				"In7.Cu" "In8.Cu" "In9.Cu" "In10.Cu" "In11.Cu" "In12.Cu" "In13.Cu" "In14.Cu"
				"In15.Cu" "In16.Cu"
			)
			(hatch none 0.5)
			(connect_pads
				(clearance 0)
			)
			(min_thickness 0.25)
			(keepout
				(tracks not_allowed)
				(vias allowed)
				(pads allowed)
				(copperpour not_allowed)
				(footprints allowed)
			)
			(placement
				(enabled no)
				(sheetname "")
			)
			(fill
				(thermal_gap 0.5)
				(thermal_bridge_width 0.5)
				(island_removal_mode 0)
			)
			(polygon
				(pts
					(arc
						(start 381.909574 4.193794)
						(mid 380.055374 4.193794)
						(end 381.909574 4.193794)
					)
				)
			)
		)
		(zone
			(layer "B.Cu")
			(hatch none 0.5)
			(connect_pads
				(clearance 0)
			)
			(min_thickness 0.25)
			(keepout
				(tracks not_allowed)
				(vias allowed)
				(pads allowed)
				(copperpour not_allowed)
				(footprints allowed)
			)
			(placement
				(enabled no)
				(sheetname "")
			)
			(fill
				(thermal_gap 0.5)
				(thermal_bridge_width 0.5)
				(island_removal_mode 0)
			)
			(polygon
				(pts
					(xy 376.981974 2.375154) (xy 376.981974 2.470658) (xy 377.578874 2.470658) (xy 377.578874 2.877058)
					(xy 376.981974 2.877058) (xy 376.981974 2.97053) (xy 377.578874 2.97053) (xy 377.578874 3.37693)
					(xy 376.981974 3.37693) (xy 376.981974 3.472434) (xy 377.680474 3.472434) (xy 377.680474 2.375154)
				)
			)
		)
	)
	(footprint ""
		(layer "B.Cu")
		(at 215.840818 -317.06566 90)
		(property "Reference" "R2497"
			(at 0 0 90)
			(layer "B.SilkS")
			(hide yes)
			(effects
				(font
					(size 1.27 1.27)
				)
				(justify mirror)
			)
		)
		(property "Value" ""
			(at 0 0 90)
			(layer "B.Fab")
			(effects
				(font
					(size 1.27 1.27)
				)
				(justify mirror)
			)
		)
		(duplicate_pad_numbers_are_jumpers no)
		(fp_line
			(start 0.7874 -0.4064)
			(end -0.7874 -0.4064)
			(stroke
				(width 0.1524)
				(type default)
			)
			(layer "B.SilkS")
		)
		(fp_line
			(start -0.7874 -0.4064)
			(end -0.7874 0.4064)
			(stroke
				(width 0.1524)
				(type default)
			)
			(layer "B.SilkS")
		)
		(fp_line
			(start 0.7874 0.4064)
			(end 0.7874 -0.4064)
			(stroke
				(width 0.1524)
				(type default)
			)
			(layer "B.SilkS")
		)
		(fp_line
			(start -0.7874 0.4064)
			(end 0.7874 0.4064)
			(stroke
				(width 0.1524)
				(type default)
			)
			(layer "B.SilkS")
		)
		(fp_line
			(start 0.67945 -0.305054)
			(end 0.12065 -0.305054)
			(stroke
				(width 0.1)
				(type default)
			)
			(layer "B.Fab")
		)
		(fp_line
			(start 0.12065 -0.305054)
			(end 0.12065 -0.2794)
			(stroke
				(width 0.1)
				(type default)
			)
			(layer "B.Fab")
		)
		(fp_line
			(start -0.12065 -0.3048)
			(end -0.67945 -0.3048)
			(stroke
				(width 0.1)
				(type default)
			)
			(layer "B.Fab")
		)
		(fp_line
			(start -0.67945 -0.3048)
			(end -0.67945 0.3048)
			(stroke
				(width 0.1)
				(type default)
			)
			(layer "B.Fab")
		)
		(fp_line
			(start 0.12065 -0.2794)
			(end -0.12065 -0.2794)
			(stroke
				(width 0.1)
				(type default)
			)
			(layer "B.Fab")
		)
		(fp_line
			(start -0.12065 -0.2794)
			(end -0.12065 -0.3048)
			(stroke
				(width 0.1)
				(type default)
			)
			(layer "B.Fab")
		)
		(fp_line
			(start 0.12065 0.2794)
			(end 0.12065 0.3048)
			(stroke
				(width 0.1)
				(type default)
			)
			(layer "B.Fab")
		)
		(fp_line
			(start -0.120396 0.2794)
			(end 0.12065 0.2794)
			(stroke
				(width 0.1)
				(type default)
			)
			(layer "B.Fab")
		)
		(fp_line
			(start 0.67945 0.3048)
			(end 0.67945 -0.305054)
			(stroke
				(width 0.1)
				(type default)
			)
			(layer "B.Fab")
		)
		(fp_line
			(start 0.12065 0.3048)
			(end 0.67945 0.3048)
			(stroke
				(width 0.1)
				(type default)
			)
			(layer "B.Fab")
		)
		(fp_line
			(start -0.120396 0.3048)
			(end -0.120396 0.2794)
			(stroke
				(width 0.1)
				(type default)
			)
			(layer "B.Fab")
		)
		(fp_line
			(start -0.67945 0.3048)
			(end -0.120396 0.3048)
			(stroke
				(width 0.1)
				(type default)
			)
			(layer "B.Fab")
		)
		(pad "1" smd circle
			(at 0.40005 0 270)
			(size 0 0)
			(layers "B.Cu" "B.Mask" "B.Paste")
			(net "PWRGD_FAIL_CPU1_GH")
		)
		(pad "2" smd circle
			(at -0.40005 0 270)
			(size 0 0)
			(layers "B.Cu" "B.Mask" "B.Paste")
			(net "PWRGD_FAIL_CPU1_GH_R1")
		)
	)
	(footprint ""
		(layer "B.Cu")
		(at 162.306 -13.426948 90)
		(property "Reference" "R4506"
			(at 0 0 90)
			(layer "B.SilkS")
			(hide yes)
			(effects
				(font
					(size 1.27 1.27)
				)
				(justify mirror)
			)
		)
		(property "Value" ""
			(at 0 0 90)
			(layer "B.Fab")
			(effects
				(font
					(size 1.27 1.27)
				)
				(justify mirror)
			)
		)
		(duplicate_pad_numbers_are_jumpers no)
		(fp_line
			(start 0.7874 -0.4064)
			(end -0.7874 -0.4064)
			(stroke
				(width 0.1524)
				(type default)
			)
			(layer "B.SilkS")
		)
		(fp_line
			(start -0.7874 -0.4064)
			(end -0.7874 0.4064)
			(stroke
				(width 0.1524)
				(type default)
			)
			(layer "B.SilkS")
		)
		(fp_line
			(start 0.7874 0.4064)
			(end 0.7874 -0.4064)
			(stroke
				(width 0.1524)
				(type default)
			)
			(layer "B.SilkS")
		)
		(fp_line
			(start -0.7874 0.4064)
			(end 0.7874 0.4064)
			(stroke
				(width 0.1524)
				(type default)
			)
			(layer "B.SilkS")
		)
		(fp_line
			(start 0.67945 -0.305054)
			(end 0.12065 -0.305054)
			(stroke
				(width 0.1)
				(type default)
			)
			(layer "B.Fab")
		)
		(fp_line
			(start 0.12065 -0.305054)
			(end 0.12065 -0.2794)
			(stroke
				(width 0.1)
				(type default)
			)
			(layer "B.Fab")
		)
		(fp_line
			(start -0.12065 -0.3048)
			(end -0.67945 -0.3048)
			(stroke
				(width 0.1)
				(type default)
			)
			(layer "B.Fab")
		)
		(fp_line
			(start -0.67945 -0.3048)
			(end -0.67945 0.3048)
			(stroke
				(width 0.1)
				(type default)
			)
			(layer "B.Fab")
		)
		(fp_line
			(start 0.12065 -0.2794)
			(end -0.12065 -0.2794)
			(stroke
				(width 0.1)
				(type default)
			)
			(layer "B.Fab")
		)
		(fp_line
			(start -0.12065 -0.2794)
			(end -0.12065 -0.3048)
			(stroke
				(width 0.1)
				(type default)
			)
			(layer "B.Fab")
		)
		(fp_line
			(start 0.12065 0.2794)
			(end 0.12065 0.3048)
			(stroke
				(width 0.1)
				(type default)
			)
			(layer "B.Fab")
		)
		(fp_line
			(start -0.120396 0.2794)
			(end 0.12065 0.2794)
			(stroke
				(width 0.1)
				(type default)
			)
			(layer "B.Fab")
		)
		(fp_line
			(start 0.67945 0.3048)
			(end 0.67945 -0.305054)
			(stroke
				(width 0.1)
				(type default)
			)
			(layer "B.Fab")
		)
		(fp_line
			(start 0.12065 0.3048)
			(end 0.67945 0.3048)
			(stroke
				(width 0.1)
				(type default)
			)
			(layer "B.Fab")
		)
		(fp_line
			(start -0.120396 0.3048)
			(end -0.120396 0.2794)
			(stroke
				(width 0.1)
				(type default)
			)
			(layer "B.Fab")
		)
		(fp_line
			(start -0.67945 0.3048)
			(end -0.120396 0.3048)
			(stroke
				(width 0.1)
				(type default)
			)
			(layer "B.Fab")
		)
		(pad "1" smd circle
			(at 0.40005 0 270)
			(size 0 0)
			(layers "B.Cu" "B.Mask" "B.Paste")
			(net "SMB_SML0_3V3AUX_SCL")
		)
		(pad "2" smd circle
			(at -0.40005 0 270)
			(size 0 0)
			(layers "B.Cu" "B.Mask" "B.Paste")
			(net "SMB_SML0_3V3AUX_SCL_R1")
		)
	)
)
